# T6G (Grand Teton) — schematic netlist excerpt (pin names and nets, part order shuffled) for the footprints in the layout excerpt that follows; sources: Cadence DE-HDL packaged netlist, KiCad conversion of 04192023_DAF0TMB3IC0_F0TG_MB_C_brd_V02_OCP.brd

R555  Q_RES  1 1% CHIP  pkg 0603LF  page 183 : A = P3V3_9ZXL045_P1 ; B = P3V3_9ZXL045_P1_VDDR
R6173  Q_RES  1K 1% EMPTY  pkg 0402LF  page 112 : A = P3V3_AUX ; B = FM_P2E_BUF2_EQA0

(kicad_pcb
	(version 20260206)
	(generator "pcbnew")
	(generator_version "10.0")
	(general
		(thickness 1.6)
		(legacy_teardrops no)
	)
	(paper "A4")
	(title_block
		(title "04192023_DAF0TMB3IC0_F0TG_MB_C_brd_V02_OCP.brd")
		(comment 1 "Grand Teton / footprints 1741-1742 of 8354")
	)
	(layers
		(0 "F.Cu" signal "TOP")
		(4 "In1.Cu" signal "GND")
		(6 "In2.Cu" signal "IN1")
		(8 "In3.Cu" signal "GND1")
		(10 "In4.Cu" signal "IN2")
		(12 "In5.Cu" signal "GND2")
		(14 "In6.Cu" signal "IN3")
		(16 "In7.Cu" signal "GND3")
		(18 "In8.Cu" signal "VCC")
		(20 "In9.Cu" signal "VCC1")
		(22 "In10.Cu" signal "GND4")
		(24 "In11.Cu" signal "IN4")
		(26 "In12.Cu" signal "GND5")
		(28 "In13.Cu" signal "IN5")
		(30 "In14.Cu" signal "GND6")
		(32 "In15.Cu" signal "IN6")
		(34 "In16.Cu" signal "GND7")
		(2 "B.Cu" signal "BOTTOM")
		(9 "F.Adhes" user "F.Adhesive")
		(11 "B.Adhes" user "B.Adhesive")
		(13 "F.Paste" user "Package Geometry/Pastemask Top")
		(15 "B.Paste" user "Package Geometry/Pastemask Bottom")
		(5 "F.SilkS" user "Ref Des/Silkscreen Top")
		(7 "B.SilkS" user "Ref Des/Silkscreen Bottom")
		(1 "F.Mask" user "Board Geometry/Soldermask Top")
		(3 "B.Mask" user "Board Geometry/Soldermask Bottom")
		(17 "Dwgs.User" user "User.Drawings")
		(19 "Cmts.User" user "User.Comments")
		(21 "Eco1.User" user "User.Eco1")
		(23 "Eco2.User" user "User.Eco2")
		(25 "Edge.Cuts" user "Board Geometry/Outline")
		(27 "Margin" user)
		(31 "F.CrtYd" user "Package Geometry/Place Bound Top")
		(29 "B.CrtYd" user "Package Geometry/Place Bound Bottom")
		(35 "F.Fab" user "Ref Des/Assembly Top")
		(33 "B.Fab" user "Ref Des/Assembly Bottom")
	)
	(footprint ""
		(layer "F.Cu")
		(at 108.458 -417.703 180)
		(property "Reference" "R555"
			(at 0 0 180)
			(layer "F.SilkS")
			(hide yes)
			(effects
				(font
					(size 1.27 1.27)
				)
			)
		)
		(property "Value" ""
			(at 0 0 180)
			(layer "F.Fab")
			(effects
				(font
					(size 1.27 1.27)
				)
			)
		)
		(duplicate_pad_numbers_are_jumpers no)
		(fp_line
			(start 1.2954 0.5842)
			(end -1.2954 0.5842)
			(stroke
				(width 0.1524)
				(type default)
			)
			(layer "F.SilkS")
		)
		(fp_line
			(start 1.2954 -0.5842)
			(end 1.2954 0.5842)
			(stroke
				(width 0.1524)
				(type default)
			)
			(layer "F.SilkS")
		)
		(fp_line
			(start -1.2954 0.5842)
			(end -1.2954 -0.5842)
			(stroke
				(width 0.1524)
				(type default)
			)
			(layer "F.SilkS")
		)
		(fp_line
			(start -1.2954 -0.5842)
			(end 1.2954 -0.5842)
			(stroke
				(width 0.1524)
				(type default)
			)
			(layer "F.SilkS")
		)
		(fp_line
			(start 1.1938 0.4064)
			(end 0.8636 0.4064)
			(stroke
				(width 0.1)
				(type default)
			)
			(layer "F.Fab")
		)
		(fp_line
			(start 1.1938 -0.406654)
			(end 1.1938 0.4064)
			(stroke
				(width 0.1)
				(type default)
			)
			(layer "F.Fab")
		)
		(fp_line
			(start 0.8636 0.4572)
			(end -0.8636 0.4572)
			(stroke
				(width 0.1)
				(type default)
			)
			(layer "F.Fab")
		)
		(fp_line
			(start 0.8636 0.4064)
			(end 0.8636 0.4572)
			(stroke
				(width 0.1)
				(type default)
			)
			(layer "F.Fab")
		)
		(fp_line
			(start 0.8636 -0.406654)
			(end 1.1938 -0.406654)
			(stroke
				(width 0.1)
				(type default)
			)
			(layer "F.Fab")
		)
		(fp_line
			(start 0.8636 -0.4572)
			(end 0.8636 -0.406654)
			(stroke
				(width 0.1)
				(type default)
			)
			(layer "F.Fab")
		)
		(fp_line
			(start -0.8636 0.4572)
			(end -0.8636 0.4318)
			(stroke
				(width 0.1)
				(type default)
			)
			(layer "F.Fab")
		)
		(fp_line
			(start -0.8636 0.4318)
			(end -0.8636 0.4064)
			(stroke
				(width 0.1)
				(type default)
			)
			(layer "F.Fab")
		)
		(fp_line
			(start -0.8636 0.4064)
			(end -1.1938 0.4064)
			(stroke
				(width 0.1)
				(type default)
			)
			(layer "F.Fab")
		)
		(fp_line
			(start -0.8636 -0.406654)
			(end -0.8636 -0.4572)
			(stroke
				(width 0.1)
				(type default)
			)
			(layer "F.Fab")
		)
		(fp_line
			(start -0.8636 -0.4572)
			(end 0.8636 -0.4572)
			(stroke
				(width 0.1)
				(type default)
			)
			(layer "F.Fab")
		)
		(fp_line
			(start -1.1938 0.4064)
			(end -1.1938 -0.406654)
			(stroke
				(width 0.1)
				(type default)
			)
			(layer "F.Fab")
		)
		(fp_line
			(start -1.1938 -0.406654)
			(end -0.8636 -0.406654)
			(stroke
				(width 0.1)
				(type default)
			)
			(layer "F.Fab")
		)
		(pad "1" smd rect
			(at -0.7366 0 90)
			(size 0.7112 0.8128)
			(layers "F.Cu" "F.Mask" "F.Paste")
			(net "P3V3_9ZXL045_P1")
		)
		(pad "2" smd rect
			(at 0.7366 0 90)
			(size 0.7112 0.8128)
			(layers "F.Cu" "F.Mask" "F.Paste")
			(net "P3V3_9ZXL045_P1_VDDR")
		)
	)
	(footprint ""
		(layer "F.Cu")
		(at 9.379458 -422.551098)
		(property "Reference" "R6173"
			(at 0 0 0)
			(layer "F.SilkS")
			(hide yes)
			(effects
				(font
					(size 1.27 1.27)
				)
			)
		)
		(property "Value" ""
			(at 0 0 0)
			(layer "F.Fab")
			(effects
				(font
					(size 1.27 1.27)
				)
			)
		)
		(duplicate_pad_numbers_are_jumpers no)
		(fp_line
			(start -0.7874 -0.4064)
			(end 0.7874 -0.4064)
			(stroke
				(width 0.1524)
				(type default)
			)
			(layer "F.SilkS")
		)
		(fp_line
			(start -0.7874 0.4064)
			(end -0.7874 -0.4064)
			(stroke
				(width 0.1524)
				(type default)
			)
			(layer "F.SilkS")
		)
		(fp_line
			(start 0.7874 -0.4064)
			(end 0.7874 0.4064)
			(stroke
				(width 0.1524)
				(type default)
			)
			(layer "F.SilkS")
		)
		(fp_line
			(start 0.7874 0.4064)
			(end -0.7874 0.4064)
			(stroke
				(width 0.1524)
				(type default)
			)
			(layer "F.SilkS")
		)
		(fp_line
			(start -0.67945 -0.305054)
			(end -0.12065 -0.305054)
			(stroke
				(width 0.1)
				(type default)
			)
			(layer "F.Fab")
		)
		(fp_line
			(start -0.67945 0.3048)
			(end -0.67945 -0.305054)
			(stroke
				(width 0.1)
				(type default)
			)
			(layer "F.Fab")
		)
		(fp_line
			(start -0.12065 -0.305054)
			(end -0.12065 -0.2794)
			(stroke
				(width 0.1)
				(type default)
			)
			(layer "F.Fab")
		)
		(fp_line
			(start -0.12065 -0.2794)
			(end 0.12065 -0.2794)
			(stroke
				(width 0.1)
				(type default)
			)
			(layer "F.Fab")
		)
		(fp_line
			(start -0.12065 0.2794)
			(end -0.12065 0.3048)
			(stroke
				(width 0.1)
				(type default)
			)
			(layer "F.Fab")
		)
		(fp_line
			(start -0.12065 0.3048)
			(end -0.67945 0.3048)
			(stroke
				(width 0.1)
				(type default)
			)
			(layer "F.Fab")
		)
		(fp_line
			(start 0.120396 0.2794)
			(end -0.12065 0.2794)
			(stroke
				(width 0.1)
				(type default)
			)
			(layer "F.Fab")
		)
		(fp_line
			(start 0.120396 0.3048)
			(end 0.120396 0.2794)
			(stroke
				(width 0.1)
				(type default)
			)
			(layer "F.Fab")
		)
		(fp_line
			(start 0.12065 -0.3048)
			(end 0.67945 -0.3048)
			(stroke
				(width 0.1)
				(type default)
			)
			(layer "F.Fab")
		)
		(fp_line
			(start 0.12065 -0.2794)
			(end 0.12065 -0.3048)
			(stroke
				(width 0.1)
				(type default)
			)
			(layer "F.Fab")
		)
		(fp_line
			(start 0.67945 -0.3048)
			(end 0.67945 0.3048)
			(stroke
				(width 0.1)
				(type default)
			)
			(layer "F.Fab")
		)
		(fp_line
			(start 0.67945 0.3048)
			(end 0.120396 0.3048)
			(stroke
				(width 0.1)
				(type default)
			)
			(layer "F.Fab")
		)
		(pad "1" smd circle
			(at -0.40005 0)
			(size 0 0)
			(layers "F.Cu" "F.Mask" "F.Paste")
			(net "P3V3_AUX")
		)
		(pad "2" smd circle
			(at 0.40005 0)
			(size 0 0)
			(layers "F.Cu" "F.Mask" "F.Paste")
			(net "FM_P2E_BUF2_EQA0")
		)
	)
)
